# S9S_MB_2U (Grand Teton) — schematic netlist excerpt (pin names and nets, part order shuffled) for the footprints in the layout excerpt that follows; sources: Cadence DE-HDL packaged netlist, KiCad conversion of 03242023_DA0F0TMBIJ0_F0T_Motherboard_J_brd_V01_OCP.brd

PR3795  Q_RES  25.5K 1% CHIP  pkg 0402LF  page 162 : A = P3V3_AUX ; B = P3V3_OCP_UV_2
C817  Q_CAP_DIFFBUS  DIFF BUS_0.22UF 6.3V 20% X6S  pkg C0201  page 175 : \1\ = P5E_CPU1_PE1_TX_C_DP<10> ; \2\ = P5E_CPU1_PE1_TX_DP<10>
R1558  Q_RES  10K 1% EMPTY  pkg 0402LF  page 220 : A = FM_CPU_RMCA_CATERR_LVT3_R_N ; B = P3V3_AUX

(kicad_pcb
	(version 20260206)
	(generator "pcbnew")
	(generator_version "10.0")
	(general
		(thickness 1.6)
		(legacy_teardrops no)
	)
	(paper "A4")
	(title_block
		(title "03242023_DA0F0TMBIJ0_F0T_Motherboard_J_brd_V01_OCP.brd")
		(comment 1 "Grand Teton / footprints 3319-3321 of 6105")
	)
	(layers
		(0 "F.Cu" signal "TOP")
		(4 "In1.Cu" signal "GND")
		(6 "In2.Cu" signal "IN1")
		(8 "In3.Cu" signal "GND1")
		(10 "In4.Cu" signal "IN2")
		(12 "In5.Cu" signal "GND2")
		(14 "In6.Cu" signal "IN3")
		(16 "In7.Cu" signal "GND3")
		(18 "In8.Cu" signal "VCC")
		(20 "In9.Cu" signal "VCC1")
		(22 "In10.Cu" signal "GND4")
		(24 "In11.Cu" signal "IN4")
		(26 "In12.Cu" signal "GND5")
		(28 "In13.Cu" signal "IN5")
		(30 "In14.Cu" signal "GND6")
		(32 "In15.Cu" signal "IN6")
		(34 "In16.Cu" signal "GND7")
		(2 "B.Cu" signal "BOTTOM")
		(9 "F.Adhes" user "F.Adhesive")
		(11 "B.Adhes" user "B.Adhesive")
		(13 "F.Paste" user "Package Geometry/Pastemask Top")
		(15 "B.Paste" user "Package Geometry/Pastemask Bottom")
		(5 "F.SilkS" user "Ref Des/Silkscreen Top")
		(7 "B.SilkS" user "Ref Des/Silkscreen Bottom")
		(1 "F.Mask" user "Board Geometry/Soldermask Top")
		(3 "B.Mask" user "Board Geometry/Soldermask Bottom")
		(17 "Dwgs.User" user "User.Drawings")
		(19 "Cmts.User" user "User.Comments")
		(21 "Eco1.User" user "User.Eco1")
		(23 "Eco2.User" user "User.Eco2")
		(25 "Edge.Cuts" user "Board Geometry/Outline")
		(27 "Margin" user)
		(31 "F.CrtYd" user "Package Geometry/Place Bound Top")
		(29 "B.CrtYd" user "Package Geometry/Place Bound Bottom")
		(35 "F.Fab" user "Ref Des/Assembly Top")
		(33 "B.Fab" user "Ref Des/Assembly Bottom")
	)
	(footprint ""
		(layer "F.Cu")
		(at 30.392878 -17.623536 90)
		(property "Reference" "C817"
			(at 0 0 90)
			(layer "F.SilkS")
			(hide yes)
			(effects
				(font
					(size 1.27 1.27)
				)
			)
		)
		(property "Value" ""
			(at 0 0 90)
			(layer "F.Fab")
			(effects
				(font
					(size 1.27 1.27)
				)
			)
		)
		(duplicate_pad_numbers_are_jumpers no)
		(fp_line
			(start 0.299974 -0.150114)
			(end 0.299974 0.150114)
			(stroke
				(width 0.1)
				(type default)
			)
			(layer "F.Fab")
		)
		(fp_line
			(start -0.299974 -0.150114)
			(end 0.299974 -0.150114)
			(stroke
				(width 0.1)
				(type default)
			)
			(layer "F.Fab")
		)
		(fp_line
			(start 0.299974 0.150114)
			(end -0.299974 0.150114)
			(stroke
				(width 0.1)
				(type default)
			)
			(layer "F.Fab")
		)
		(fp_line
			(start -0.299974 0.150114)
			(end -0.299974 -0.150114)
			(stroke
				(width 0.1)
				(type default)
			)
			(layer "F.Fab")
		)
		(pad "1" smd rect
			(at -0.2667 0 90)
			(size 0.3048 0.381)
			(layers "F.Cu" "F.Mask" "F.Paste")
			(net "P5E_CPU1_PE1_TX_C_DP<10>")
		)
		(pad "2" smd rect
			(at 0.2667 0 90)
			(size 0.3048 0.381)
			(layers "F.Cu" "F.Mask" "F.Paste")
			(net "P5E_CPU1_PE1_TX_DP<10>")
		)
	)
	(footprint ""
		(layer "F.Cu")
		(at 80.77073 -59.372246 -90)
		(property "Reference" "PR3795"
			(at 0 0 270)
			(layer "F.SilkS")
			(hide yes)
			(effects
				(font
					(size 1.27 1.27)
				)
			)
		)
		(property "Value" ""
			(at 0 0 270)
			(layer "F.Fab")
			(effects
				(font
					(size 1.27 1.27)
				)
			)
		)
		(duplicate_pad_numbers_are_jumpers no)
		(fp_line
			(start -0.7874 0.4064)
			(end -0.7874 -0.4064)
			(stroke
				(width 0.1524)
				(type default)
			)
			(layer "F.SilkS")
		)
		(fp_line
			(start 0.7874 0.4064)
			(end -0.7874 0.4064)
			(stroke
				(width 0.1524)
				(type default)
			)
			(layer "F.SilkS")
		)
		(fp_line
			(start -0.7874 -0.4064)
			(end 0.7874 -0.4064)
			(stroke
				(width 0.1524)
				(type default)
			)
			(layer "F.SilkS")
		)
		(fp_line
			(start 0.7874 -0.4064)
			(end 0.7874 0.4064)
			(stroke
				(width 0.1524)
				(type default)
			)
			(layer "F.SilkS")
		)
		(fp_line
			(start -0.67945 0.3048)
			(end -0.67945 -0.305054)
			(stroke
				(width 0.1)
				(type default)
			)
			(layer "F.Fab")
		)
		(fp_line
			(start -0.12065 0.3048)
			(end -0.67945 0.3048)
			(stroke
				(width 0.1)
				(type default)
			)
			(layer "F.Fab")
		)
		(fp_line
			(start 0.120396 0.3048)
			(end 0.120396 0.2794)
			(stroke
				(width 0.1)
				(type default)
			)
			(layer "F.Fab")
		)
		(fp_line
			(start 0.67945 0.3048)
			(end 0.120396 0.3048)
			(stroke
				(width 0.1)
				(type default)
			)
			(layer "F.Fab")
		)
		(fp_line
			(start -0.12065 0.2794)
			(end -0.12065 0.3048)
			(stroke
				(width 0.1)
				(type default)
			)
			(layer "F.Fab")
		)
		(fp_line
			(start 0.120396 0.2794)
			(end -0.12065 0.2794)
			(stroke
				(width 0.1)
				(type default)
			)
			(layer "F.Fab")
		)
		(fp_line
			(start -0.12065 -0.2794)
			(end 0.12065 -0.2794)
			(stroke
				(width 0.1)
				(type default)
			)
			(layer "F.Fab")
		)
		(fp_line
			(start 0.12065 -0.2794)
			(end 0.12065 -0.3048)
			(stroke
				(width 0.1)
				(type default)
			)
			(layer "F.Fab")
		)
		(fp_line
			(start 0.12065 -0.3048)
			(end 0.67945 -0.3048)
			(stroke
				(width 0.1)
				(type default)
			)
			(layer "F.Fab")
		)
		(fp_line
			(start 0.67945 -0.3048)
			(end 0.67945 0.3048)
			(stroke
				(width 0.1)
				(type default)
			)
			(layer "F.Fab")
		)
		(fp_line
			(start -0.67945 -0.305054)
			(end -0.12065 -0.305054)
			(stroke
				(width 0.1)
				(type default)
			)
			(layer "F.Fab")
		)
		(fp_line
			(start -0.12065 -0.305054)
			(end -0.12065 -0.2794)
			(stroke
				(width 0.1)
				(type default)
			)
			(layer "F.Fab")
		)
		(pad "1" smd circle
			(at -0.40005 0 270)
			(size 0 0)
			(layers "F.Cu" "F.Mask" "F.Paste")
			(net "P3V3_AUX")
		)
		(pad "2" smd circle
			(at 0.40005 0 270)
			(size 0 0)
			(layers "F.Cu" "F.Mask" "F.Paste")
			(net "P3V3_OCP_UV_2")
		)
	)
	(footprint ""
		(layer "F.Cu")
		(at 193.60388 -108.765848)
		(property "Reference" "R1558"
			(at 0 0 0)
			(layer "F.SilkS")
			(hide yes)
			(effects
				(font
					(size 1.27 1.27)
				)
			)
		)
		(property "Value" ""
			(at 0 0 0)
			(layer "F.Fab")
			(effects
				(font
					(size 1.27 1.27)
				)
			)
		)
		(duplicate_pad_numbers_are_jumpers no)
		(fp_line
			(start -0.7874 -0.4064)
			(end 0.7874 -0.4064)
			(stroke
				(width 0.1524)
				(type default)
			)
			(layer "F.SilkS")
		)
		(fp_line
			(start -0.7874 0.4064)
			(end -0.7874 -0.4064)
			(stroke
				(width 0.1524)
				(type default)
			)
			(layer "F.SilkS")
		)
		(fp_line
			(start 0.7874 -0.4064)
			(end 0.7874 0.4064)
			(stroke
				(width 0.1524)
				(type default)
			)
			(layer "F.SilkS")
		)
		(fp_line
			(start 0.7874 0.4064)
			(end -0.7874 0.4064)
			(stroke
				(width 0.1524)
				(type default)
			)
			(layer "F.SilkS")
		)
		(fp_line
			(start -0.67945 -0.305054)
			(end -0.12065 -0.305054)
			(stroke
				(width 0.1)
				(type default)
			)
			(layer "F.Fab")
		)
		(fp_line
			(start -0.67945 0.3048)
			(end -0.67945 -0.305054)
			(stroke
				(width 0.1)
				(type default)
			)
			(layer "F.Fab")
		)
		(fp_line
			(start -0.12065 -0.305054)
			(end -0.12065 -0.2794)
			(stroke
				(width 0.1)
				(type default)
			)
			(layer "F.Fab")
		)
		(fp_line
			(start -0.12065 -0.2794)
			(end 0.12065 -0.2794)
			(stroke
				(width 0.1)
				(type default)
			)
			(layer "F.Fab")
		)
		(fp_line
			(start -0.12065 0.2794)
			(end -0.12065 0.3048)
			(stroke
				(width 0.1)
				(type default)
			)
			(layer "F.Fab")
		)
		(fp_line
			(start -0.12065 0.3048)
			(end -0.67945 0.3048)
			(stroke
				(width 0.1)
				(type default)
			)
			(layer "F.Fab")
		)
		(fp_line
			(start 0.120396 0.2794)
			(end -0.12065 0.2794)
			(stroke
				(width 0.1)
				(type default)
			)
			(layer "F.Fab")
		)
		(fp_line
			(start 0.120396 0.3048)
			(end 0.120396 0.2794)
			(stroke
				(width 0.1)
				(type default)
			)
			(layer "F.Fab")
		)
		(fp_line
			(start 0.12065 -0.3048)
			(end 0.67945 -0.3048)
			(stroke
				(width 0.1)
				(type default)
			)
			(layer "F.Fab")
		)
		(fp_line
			(start 0.12065 -0.2794)
			(end 0.12065 -0.3048)
			(stroke
				(width 0.1)
				(type default)
			)
			(layer "F.Fab")
		)
		(fp_line
			(start 0.67945 -0.3048)
			(end 0.67945 0.3048)
			(stroke
				(width 0.1)
				(type default)
			)
			(layer "F.Fab")
		)
		(fp_line
			(start 0.67945 0.3048)
			(end 0.120396 0.3048)
			(stroke
				(width 0.1)
				(type default)
			)
			(layer "F.Fab")
		)
		(pad "1" smd circle
			(at -0.40005 0)
			(size 0 0)
			(layers "F.Cu" "F.Mask" "F.Paste")
			(net "FM_CPU_RMCA_CATERR_LVT3_R_N")
		)
		(pad "2" smd circle
			(at 0.40005 0)
			(size 0 0)
			(layers "F.Cu" "F.Mask" "F.Paste")
			(net "P3V3_AUX")
		)
	)
)
